(kicad_pcb
	(version 20241229)
	(generator "pcbnew")
	(generator_version "9.0")
	(general
		(thickness 1.711)
		(legacy_teardrops no)
	)
	(paper "A4")
	(title_block
		(title "Antmicro Baseboard for Jetson AGX Thor")
		(date "2026-02-18")
		(rev "1.1.0")
		(company "Antmicro Ltd")
		(comment 1 "www.antmicro.com")
		(comment 9 "footprints 103-107 of 1170")
	)
	(layers
		(0 "F.Cu" signal)
		(4 "In1.Cu" signal)
		(6 "In2.Cu" signal)
		(8 "In3.Cu" signal)
		(10 "In4.Cu" jumper)
		(12 "In5.Cu" signal)
		(14 "In6.Cu" signal)
		(16 "In7.Cu" signal)
		(18 "In8.Cu" signal)
		(2 "B.Cu" signal)
		(9 "F.Adhes" user "F.Adhesive")
		(11 "B.Adhes" user "B.Adhesive")
		(13 "F.Paste" user)
		(15 "B.Paste" user)
		(5 "F.SilkS" user "F.Silkscreen")
		(7 "B.SilkS" user "B.Silkscreen")
		(1 "F.Mask" user)
		(3 "B.Mask" user)
		(17 "Dwgs.User" user "User.Drawings")
		(19 "Cmts.User" user "User.Comments")
		(21 "Eco1.User" user "User.Eco1")
		(23 "Eco2.User" user "User.Eco2")
		(25 "Edge.Cuts" user)
		(27 "Margin" user)
		(31 "F.CrtYd" user "F.Courtyard")
		(29 "B.CrtYd" user "B.Courtyard")
		(35 "F.Fab" user)
		(33 "B.Fab" user)
	)
	(footprint "antmicro-footprints:R_0402_1005Metric"
		(layer "F.Cu")
		(at 193.026 140.1 180)
		(descr "Resistor SMD 0402")
		(tags "resistor SMD 0402")
		(property "Reference" "R205"
			(at -1.574 1.6 0)
			(layer "F.SilkS")
			(effects
				(font
					(size 0.7 0.7)
					(thickness 0.15)
				)
				(justify right top)
			)
		)
		(property "Value" "R_200R_0402"
			(at -1.011843 1.772046 0)
			(layer "F.Fab")
			(effects
				(font
					(size 0.7 0.7)
					(thickness 0.15)
				)
				(justify right top)
			)
		)
		(property "Datasheet" "https://www.bourns.com/docs/product-datasheets/cr.pdf"
			(at 0 0 0)
			(layer "F.Fab")
			(hide yes)
			(effects
				(font
					(size 1.27 1.27)
					(thickness 0.15)
				)
			)
		)
		(property "Description" "SMD Chip Resistor, 200 ohm, ± 1%, 62.5 mW, 0402 [1005 Metric], Thick Film, General Purpose"
			(at 0 0 0)
			(layer "F.Fab")
			(hide yes)
			(effects
				(font
					(size 1.27 1.27)
					(thickness 0.15)
				)
			)
		)
		(property "MPN" "CR0402-FX-2000GLF"
			(at 0 0 180)
			(unlocked yes)
			(layer "F.Fab")
			(hide yes)
			(effects
				(font
					(size 1 1)
					(thickness 0.15)
				)
			)
		)
		(property "Manufacturer" "Bourns"
			(at 0 0 180)
			(unlocked yes)
			(layer "F.Fab")
			(hide yes)
			(effects
				(font
					(size 1 1)
					(thickness 0.15)
				)
			)
		)
		(property "License" "Apache-2.0"
			(at 0 0 180)
			(unlocked yes)
			(layer "F.Fab")
			(hide yes)
			(effects
				(font
					(size 1 1)
					(thickness 0.15)
				)
			)
		)
		(property "Author" "Antmicro"
			(at 0 0 180)
			(unlocked yes)
			(layer "F.Fab")
			(hide yes)
			(effects
				(font
					(size 1 1)
					(thickness 0.15)
				)
			)
		)
		(property "Val" "200R"
			(at 0 0 180)
			(unlocked yes)
			(layer "F.Fab")
			(hide yes)
			(effects
				(font
					(size 1 1)
					(thickness 0.15)
				)
			)
		)
		(property "Tolerance" "1%"
			(at 0 0 180)
			(unlocked yes)
			(layer "F.Fab")
			(hide yes)
			(effects
				(font
					(size 1 1)
					(thickness 0.15)
				)
			)
		)
		(sheetname "/SFP/")
		(sheetfile "sfp.kicad_sch")
		(attr smd)
		(fp_poly
			(pts
				(xy -0.925 -0.47) (xy 0.925 -0.47) (xy 0.925 0.47) (xy -0.925 0.47)
			)
			(stroke
				(width 0.05)
				(type default)
			)
			(fill no)
			(layer "F.CrtYd")
		)
		(fp_poly
			(pts
				(xy -0.5 -0.25) (xy 0.5 -0.25) (xy 0.5 0.25) (xy -0.5 0.25)
			)
			(stroke
				(width 0.15)
				(type solid)
			)
			(fill no)
			(layer "F.Fab")
		)
		(fp_text user "License: Apache-2.0"
			(at -0.949999 5.169 0)
			(layer "F.Fab")
			(effects
				(font
					(size 0.7 0.7)
					(thickness 0.15)
				)
				(justify right top)
			)
		)
		(fp_text user "Author: Antmicro"
			(at -0.95 4.169 0)
			(layer "F.Fab")
			(effects
				(font
					(size 0.7 0.7)
					(thickness 0.15)
				)
				(justify right top)
			)
		)
		(fp_text user "${REFERENCE}"
			(at -0.95 3.168 0)
			(layer "F.Fab")
			(effects
				(font
					(size 0.7 0.7)
					(thickness 0.15)
				)
				(justify right top)
			)
		)
		(pad "1" smd roundrect
			(at -0.48 0 180)
			(size 0.59 0.64)
			(layers "F.Cu" "F.Mask" "F.Paste")
			(roundrect_rratio 0.25)
			(net 1004 "/SFP/SFP_LEDG")
			(pintype "passive")
		)
		(pad "2" smd roundrect
			(at 0.48 0 180)
			(size 0.59 0.64)
			(layers "F.Cu" "F.Mask" "F.Paste")
			(roundrect_rratio 0.25)
			(net 530 "Net-(D14-C)")
			(pintype "passive")
		)
	)
	(footprint "antmicro-footprints:R_0402_1005Metric"
		(layer "F.Cu")
		(at 173.24 63.49 90)
		(descr "Resistor SMD 0402")
		(tags "resistor SMD 0402")
		(property "Reference" "R234"
			(at -1.01 2.36 90)
			(layer "F.SilkS")
			(effects
				(font
					(size 0.7 0.7)
					(thickness 0.15)
				)
				(justify left bottom)
			)
		)
		(property "Value" "R_200R_0402"
			(at -1.011843 1.772047 90)
			(layer "F.Fab")
			(effects
				(font
					(size 0.7 0.7)
					(thickness 0.15)
				)
				(justify left bottom)
			)
		)
		(property "Datasheet" "https://www.bourns.com/docs/product-datasheets/cr.pdf"
			(at 0 0 90)
			(layer "F.Fab")
			(hide yes)
			(effects
				(font
					(size 1.27 1.27)
					(thickness 0.15)
				)
			)
		)
		(property "Description" "SMD Chip Resistor, 200 ohm, ± 1%, 62.5 mW, 0402 [1005 Metric], Thick Film, General Purpose"
			(at 0 0 90)
			(layer "F.Fab")
			(hide yes)
			(effects
				(font
					(size 1.27 1.27)
					(thickness 0.15)
				)
			)
		)
		(property "Manufacturer" "Bourns"
			(at 0 0 90)
			(unlocked yes)
			(layer "F.Fab")
			(hide yes)
			(effects
				(font
					(size 1 1)
					(thickness 0.15)
				)
			)
		)
		(property "MPN" "CR0402-FX-2000GLF"
			(at 0 0 90)
			(unlocked yes)
			(layer "F.Fab")
			(hide yes)
			(effects
				(font
					(size 1 1)
					(thickness 0.15)
				)
			)
		)
		(property "Val" "200R"
			(at 0 0 90)
			(unlocked yes)
			(layer "F.Fab")
			(hide yes)
			(effects
				(font
					(size 1 1)
					(thickness 0.15)
				)
			)
		)
		(property "License" "Apache-2.0"
			(at 0 0 90)
			(unlocked yes)
			(layer "F.Fab")
			(hide yes)
			(effects
				(font
					(size 1 1)
					(thickness 0.15)
				)
			)
		)
		(property "Author" "Antmicro"
			(at 0 0 90)
			(unlocked yes)
			(layer "F.Fab")
			(hide yes)
			(effects
				(font
					(size 1 1)
					(thickness 0.15)
				)
			)
		)
		(property "Tolerance" "1%"
			(at 0 0 90)
			(unlocked yes)
			(layer "F.Fab")
			(hide yes)
			(effects
				(font
					(size 1 1)
					(thickness 0.15)
				)
			)
		)
		(sheetname "/Peripherals/")
		(sheetfile "peripherals.kicad_sch")
		(attr smd)
		(fp_rect
			(start -0.925 -0.47)
			(end 0.925 0.47)
			(stroke
				(width 0.05)
				(type default)
			)
			(fill no)
			(layer "F.CrtYd")
		)
		(fp_rect
			(start -0.5 -0.25)
			(end 0.5 0.25)
			(stroke
				(width 0.15)
				(type solid)
			)
			(fill no)
			(layer "F.Fab")
		)
		(fp_text user "Author: Antmicro"
			(at -0.95 4.169 90)
			(layer "F.Fab")
			(effects
				(font
					(size 0.7 0.7)
					(thickness 0.15)
				)
				(justify left bottom)
			)
		)
		(fp_text user "License: Apache-2.0"
			(at -0.95 5.169 90)
			(layer "F.Fab")
			(effects
				(font
					(size 0.7 0.7)
					(thickness 0.15)
				)
				(justify left bottom)
			)
		)
		(fp_text user "${REFERENCE}"
			(at -0.95 3.168 90)
			(layer "F.Fab")
			(effects
				(font
					(size 0.7 0.7)
					(thickness 0.15)
				)
				(justify left bottom)
			)
		)
		(pad "1" smd roundrect
			(at -0.48 0 90)
			(size 0.59 0.64)
			(layers "F.Cu" "F.Mask" "F.Paste")
			(roundrect_rratio 0.25)
			(net 38 "Net-(D36-A)")
			(pintype "passive")
		)
		(pad "2" smd roundrect
			(at 0.48 0 90)
			(size 0.59 0.64)
			(layers "F.Cu" "F.Mask" "F.Paste")
			(roundrect_rratio 0.25)
			(net 2 "+3V3")
			(pintype "passive")
		)
	)
	(footprint "antmicro-footprints:R_0402_1005Metric"
		(layer "F.Cu")
		(at 130.8 143.2 -90)
		(descr "Resistor SMD 0402")
		(tags "resistor SMD 0402")
		(property "Reference" "R348"
			(at 1 0.4 90)
			(layer "F.SilkS")
			(effects
				(font
					(size 0.7 0.7)
					(thickness 0.15)
				)
				(justify right top)
			)
		)
		(property "Value" "R_10k_0402"
			(at -1.011843 1.772046 90)
			(layer "F.Fab")
			(effects
				(font
					(size 0.7 0.7)
					(thickness 0.15)
				)
				(justify right top)
			)
		)
		(property "Datasheet" "https://www.bourns.com/docs/product-datasheets/cr.pdf"
			(at 0 0 90)
			(layer "F.Fab")
			(hide yes)
			(effects
				(font
					(size 1.27 1.27)
					(thickness 0.15)
				)
			)
		)
		(property "Description" "SMD Chip Resistor, 10 kohm, ± 1%, 62.5 mW, 0402 [1005 Metric], Thick Film, General Purpose"
			(at 0 0 90)
			(layer "F.Fab")
			(hide yes)
			(effects
				(font
					(size 1.27 1.27)
					(thickness 0.15)
				)
			)
		)
		(property "MPN" "CR0402-FX-1002GLF"
			(at 0 0 270)
			(unlocked yes)
			(layer "F.Fab")
			(hide yes)
			(effects
				(font
					(size 1 1)
					(thickness 0.15)
				)
			)
		)
		(property "Manufacturer" "Bourns"
			(at 0 0 270)
			(unlocked yes)
			(layer "F.Fab")
			(hide yes)
			(effects
				(font
					(size 1 1)
					(thickness 0.15)
				)
			)
		)
		(property "License" "Apache-2.0"
			(at 0 0 270)
			(unlocked yes)
			(layer "F.Fab")
			(hide yes)
			(effects
				(font
					(size 1 1)
					(thickness 0.15)
				)
			)
		)
		(property "Author" "Antmicro"
			(at 0 0 270)
			(unlocked yes)
			(layer "F.Fab")
			(hide yes)
			(effects
				(font
					(size 1 1)
					(thickness 0.15)
				)
			)
		)
		(property "Val" "10k"
			(at 0 0 270)
			(unlocked yes)
			(layer "F.Fab")
			(hide yes)
			(effects
				(font
					(size 1 1)
					(thickness 0.15)
				)
			)
		)
		(property "Tolerance" "1%"
			(at 0 0 270)
			(unlocked yes)
			(layer "F.Fab")
			(hide yes)
			(effects
				(font
					(size 1 1)
					(thickness 0.15)
				)
			)
		)
		(sheetname "/Expansion connector/")
		(sheetfile "expansion_connector.kicad_sch")
		(attr smd exclude_from_pos_files exclude_from_bom dnp)
		(fp_poly
			(pts
				(xy -0.925 -0.47) (xy 0.925 -0.47) (xy 0.925 0.47) (xy -0.925 0.47)
			)
			(stroke
				(width 0.05)
				(type default)
			)
			(fill no)
			(layer "F.CrtYd")
		)
		(fp_poly
			(pts
				(xy -0.5 -0.25) (xy 0.5 -0.25) (xy 0.5 0.25) (xy -0.5 0.25)
			)
			(stroke
				(width 0.15)
				(type solid)
			)
			(fill no)
			(layer "F.Fab")
		)
		(fp_text user "License: Apache-2.0"
			(at -0.949999 5.169 90)
			(layer "F.Fab")
			(effects
				(font
					(size 0.7 0.7)
					(thickness 0.15)
				)
				(justify right top)
			)
		)
		(fp_text user "${REFERENCE}"
			(at -0.95 3.168 90)
			(layer "F.Fab")
			(effects
				(font
					(size 0.7 0.7)
					(thickness 0.15)
				)
				(justify right top)
			)
		)
		(fp_text user "Author: Antmicro"
			(at -0.95 4.169 90)
			(layer "F.Fab")
			(effects
				(font
					(size 0.7 0.7)
					(thickness 0.15)
				)
				(justify right top)
			)
		)
		(pad "1" smd roundrect
			(at -0.48 0 270)
			(size 0.59 0.64)
			(layers "F.Cu" "F.Mask" "F.Paste")
			(roundrect_rratio 0.25)
			(net 472 "/Expansion connector/ADDR1")
			(pintype "passive")
		)
		(pad "2" smd roundrect
			(at 0.48 0 270)
			(size 0.59 0.64)
			(layers "F.Cu" "F.Mask" "F.Paste")
			(roundrect_rratio 0.25)
			(net 1 "GND")
			(pintype "passive")
		)
	)
	(footprint "antmicro-footprints:R_0402_1005Metric"
		(layer "F.Cu")
		(at 197.9 98.82 -90)
		(descr "Resistor SMD 0402")
		(tags "resistor SMD 0402")
		(property "Reference" "R387"
			(at -0.72 3.5 90)
			(layer "F.SilkS")
			(effects
				(font
					(size 0.7 0.7)
					(thickness 0.15)
				)
				(justify right top)
			)
		)
		(property "Value" "R_0R_0402"
			(at -1.011843 1.772047 90)
			(layer "F.Fab")
			(effects
				(font
					(size 0.7 0.7)
					(thickness 0.15)
				)
				(justify right top)
			)
		)
		(property "Datasheet" "https://industrial.panasonic.com/cdbs/www-data/pdf/RDA0000/AOA0000C301.pdf"
			(at 0 0 90)
			(layer "F.Fab")
			(hide yes)
			(effects
				(font
					(size 1.27 1.27)
					(thickness 0.15)
				)
			)
		)
		(property "Description" "SMD Chip Resistor, Jumper, 0 ohm, 100 mW, 0402 [1005 Metric], Thick Film, General Purpose"
			(at 0 0 90)
			(layer "F.Fab")
			(hide yes)
			(effects
				(font
					(size 1.27 1.27)
					(thickness 0.15)
				)
			)
		)
		(property "MPN" "ERJ2GE0R00X"
			(at 0 0 270)
			(unlocked yes)
			(layer "F.Fab")
			(hide yes)
			(effects
				(font
					(size 1 1)
					(thickness 0.15)
				)
			)
		)
		(property "Manufacturer" "Panasonic"
			(at 0 0 270)
			(unlocked yes)
			(layer "F.Fab")
			(hide yes)
			(effects
				(font
					(size 1 1)
					(thickness 0.15)
				)
			)
		)
		(property "License" "Apache-2.0"
			(at 0 0 270)
			(unlocked yes)
			(layer "F.Fab")
			(hide yes)
			(effects
				(font
					(size 1 1)
					(thickness 0.15)
				)
			)
		)
		(property "Author" "Antmicro"
			(at 0 0 270)
			(unlocked yes)
			(layer "F.Fab")
			(hide yes)
			(effects
				(font
					(size 1 1)
					(thickness 0.15)
				)
			)
		)
		(property "Val" "0R"
			(at 0 0 270)
			(unlocked yes)
			(layer "F.Fab")
			(hide yes)
			(effects
				(font
					(size 1 1)
					(thickness 0.15)
				)
			)
		)
		(property "Tolerance" "~"
			(at 0 0 270)
			(unlocked yes)
			(layer "F.Fab")
			(hide yes)
			(effects
				(font
					(size 1 1)
					(thickness 0.15)
				)
			)
		)
		(property "Current" "1A"
			(at 0 0 270)
			(unlocked yes)
			(layer "F.Fab")
			(hide yes)
			(effects
				(font
					(size 1 1)
					(thickness 0.15)
				)
			)
		)
		(sheetname "/USB Debug, PD/")
		(sheetfile "usb_debug_pd.kicad_sch")
		(attr smd exclude_from_pos_files exclude_from_bom dnp)
		(fp_rect
			(start -0.925 -0.47)
			(end 0.925 0.47)
			(stroke
				(width 0.05)
				(type default)
			)
			(fill no)
			(layer "F.CrtYd")
		)
		(fp_rect
			(start -0.5 -0.25)
			(end 0.5 0.25)
			(stroke
				(width 0.15)
				(type solid)
			)
			(fill no)
			(layer "F.Fab")
		)
		(fp_text user "Author: Antmicro"
			(at -0.95 4.169 90)
			(layer "F.Fab")
			(effects
				(font
					(size 0.7 0.7)
					(thickness 0.15)
				)
				(justify right top)
			)
		)
		(fp_text user "${REFERENCE}"
			(at -0.95 3.168 90)
			(layer "F.Fab")
			(effects
				(font
					(size 0.7 0.7)
					(thickness 0.15)
				)
				(justify right top)
			)
		)
		(fp_text user "License: Apache-2.0"
			(at -0.95 5.169 90)
			(layer "F.Fab")
			(effects
				(font
					(size 0.7 0.7)
					(thickness 0.15)
				)
				(justify right top)
			)
		)
		(pad "1" smd roundrect
			(at -0.48 0 270)
			(size 0.59 0.64)
			(layers "F.Cu" "F.Mask" "F.Paste")
			(roundrect_rratio 0.25)
			(net 810 "/USB Debug, PD/MISO")
			(pintype "passive")
		)
		(pad "2" smd roundrect
			(at 0.48 0 270)
			(size 0.59 0.64)
			(layers "F.Cu" "F.Mask" "F.Paste")
			(roundrect_rratio 0.25)
			(net 850 "/I2C_{SYS}.SDA")
			(pintype "passive")
		)
	)
	(footprint "antmicro-footprints:R_0603_1608Metric"
		(layer "F.Cu")
		(at 114.77 63.45 180)
		(descr "Resistor SMD 0603")
		(tags "resistor SMD 0603")
		(property "Reference" "R76"
			(at -1.06 -0.74 0)
			(layer "F.SilkS")
			(effects
				(font
					(size 0.7 0.7)
					(thickness 0.15)
				)
				(justify right top)
			)
		)
		(property "Value" "R_0R_22.4A_0603"
			(at 0 1.6 0)
			(layer "F.Fab")
			(effects
				(font
					(size 0.7 0.7)
					(thickness 0.15)
				)
				(justify right top)
			)
		)
		(property "Datasheet" "https://fscdn.rohm.com/en/products/databook/datasheet/passive/resistor/chip_resistor/pmr-jpw-e.pdf"
			(at 0 0 0)
			(layer "F.Fab")
			(hide yes)
			(effects
				(font
					(size 1.27 1.27)
					(thickness 0.15)
				)
			)
		)
		(property "Description" "SMD Chip Resistor"
			(at 0 0 0)
			(layer "F.Fab")
			(hide yes)
			(effects
				(font
					(size 1.27 1.27)
					(thickness 0.15)
				)
			)
		)
		(property "Manufacturer" "ROHM Semiconductor"
			(at 0 0 180)
			(unlocked yes)
			(layer "F.Fab")
			(hide yes)
			(effects
				(font
					(size 1 1)
					(thickness 0.15)
				)
			)
		)
		(property "MPN" "PMR03EZPJ000"
			(at 0 0 180)
			(unlocked yes)
			(layer "F.Fab")
			(hide yes)
			(effects
				(font
					(size 1 1)
					(thickness 0.15)
				)
			)
		)
		(property "Val" "0R"
			(at 0 0 180)
			(unlocked yes)
			(layer "F.Fab")
			(hide yes)
			(effects
				(font
					(size 1 1)
					(thickness 0.15)
				)
			)
		)
		(property "Author" "Antmicro"
			(at 0 0 180)
			(unlocked yes)
			(layer "F.Fab")
			(hide yes)
			(effects
				(font
					(size 1 1)
					(thickness 0.15)
				)
			)
		)
		(property "License" "Apache-2.0"
			(at 0 0 180)
			(unlocked yes)
			(layer "F.Fab")
			(hide yes)
			(effects
				(font
					(size 1 1)
					(thickness 0.15)
				)
			)
		)
		(property "Max. Curr." "22.4A"
			(at 0 0 180)
			(unlocked yes)
			(layer "F.Fab")
			(hide yes)
			(effects
				(font
					(size 1 1)
					(thickness 0.15)
				)
			)
		)
		(property "Tolerance" "template_tolerance"
			(at 0 0 180)
			(unlocked yes)
			(layer "F.Fab")
			(hide yes)
			(effects
				(font
					(size 1 1)
					(thickness 0.15)
				)
			)
		)
		(sheetname "/SoM_Power/")
		(sheetfile "som_power.kicad_sch")
		(attr smd)
		(fp_line
			(start -0.15 0.4)
			(end 0.15 0.4)
			(stroke
				(width 0.15)
				(type solid)
			)
			(layer "F.SilkS")
		)
		(fp_line
			(start -0.15 -0.4)
			(end 0.15 -0.4)
			(stroke
				(width 0.15)
				(type solid)
			)
			(layer "F.SilkS")
		)
		(fp_poly
			(pts
				(xy -1.25 -0.65) (xy 1.25 -0.65) (xy 1.25 0.65) (xy -1.25 0.65)
			)
			(stroke
				(width 0.05)
				(type solid)
			)
			(fill no)
			(layer "F.CrtYd")
		)
		(fp_poly
			(pts
				(xy -0.8 -0.4) (xy 0.8 -0.4) (xy 0.8 0.4) (xy -0.8 0.4)
			)
			(stroke
				(width 0.15)
				(type solid)
			)
			(fill no)
			(layer "F.Fab")
		)
		(fp_text user "License: Apache-2.0"
			(at -1.249999 5.9 0)
			(layer "F.Fab")
			(effects
				(font
					(size 0.7 0.7)
					(thickness 0.15)
				)
				(justify right top)
			)
		)
		(fp_text user "${REFERENCE}"
			(at -1.25 3.898 0)
			(layer "F.Fab")
			(effects
				(font
					(size 0.7 0.7)
					(thickness 0.15)
				)
				(justify right top)
			)
		)
		(fp_text user "Author: Antmicro"
			(at -1.25 4.9 0)
			(layer "F.Fab")
			(effects
				(font
					(size 0.7 0.7)
					(thickness 0.15)
				)
				(justify right top)
			)
		)
		(pad "1" smd roundrect
			(at -0.7 0 180)
			(size 0.8 1)
			(layers "F.Cu" "F.Mask" "F.Paste")
			(roundrect_rratio 0.2)
			(net 1096 "Net-(Q9-D)")
			(pintype "passive")
		)
		(pad "2" smd roundrect
			(at 0.7 0 180)
			(size 0.8 1)
			(layers "F.Cu" "F.Mask" "F.Paste")
			(roundrect_rratio 0.2)
			(net 213 "+5V_SOM")
			(pintype "passive")
		)
	)
)
